# S9S_MB_2U (Grand Teton) — schematic netlist excerpt (pin names and nets, part order shuffled) for the footprints in the layout excerpt that follows; sources: Cadence DE-HDL packaged netlist, KiCad conversion of 03242023_DA0F0TMBIJ0_F0T_Motherboard_J_brd_V01_OCP.brd

PC2227  Q_CAP  0.068UF 16V 10% X7R  pkg 0402  page 303 : A = HSC_SS ; B = AGND_HSC
R3143  Q_RES  0 5% CHIP  pkg 0402LF  page 162 : A = HP_LVC3_OCP_V3_2_PRSNT2_N_R ; B = HP_LVC3_OCP_V3_2_ATTN_OUT_SW_N

(kicad_pcb
	(version 20260206)
	(generator "pcbnew")
	(generator_version "10.0")
	(general
		(thickness 1.6)
		(legacy_teardrops no)
	)
	(paper "A4")
	(title_block
		(title "03242023_DA0F0TMBIJ0_F0T_Motherboard_J_brd_V01_OCP.brd")
		(comment 1 "Grand Teton / footprints 608-609 of 6105")
	)
	(layers
		(0 "F.Cu" signal "TOP")
		(4 "In1.Cu" signal "GND")
		(6 "In2.Cu" signal "IN1")
		(8 "In3.Cu" signal "GND1")
		(10 "In4.Cu" signal "IN2")
		(12 "In5.Cu" signal "GND2")
		(14 "In6.Cu" signal "IN3")
		(16 "In7.Cu" signal "GND3")
		(18 "In8.Cu" signal "VCC")
		(20 "In9.Cu" signal "VCC1")
		(22 "In10.Cu" signal "GND4")
		(24 "In11.Cu" signal "IN4")
		(26 "In12.Cu" signal "GND5")
		(28 "In13.Cu" signal "IN5")
		(30 "In14.Cu" signal "GND6")
		(32 "In15.Cu" signal "IN6")
		(34 "In16.Cu" signal "GND7")
		(2 "B.Cu" signal "BOTTOM")
		(9 "F.Adhes" user "F.Adhesive")
		(11 "B.Adhes" user "B.Adhesive")
		(13 "F.Paste" user "Package Geometry/Pastemask Top")
		(15 "B.Paste" user "Package Geometry/Pastemask Bottom")
		(5 "F.SilkS" user "Ref Des/Silkscreen Top")
		(7 "B.SilkS" user "Ref Des/Silkscreen Bottom")
		(1 "F.Mask" user "Board Geometry/Soldermask Top")
		(3 "B.Mask" user "Board Geometry/Soldermask Bottom")
		(17 "Dwgs.User" user "User.Drawings")
		(19 "Cmts.User" user "User.Comments")
		(21 "Eco1.User" user "User.Eco1")
		(23 "Eco2.User" user "User.Eco2")
		(25 "Edge.Cuts" user "Board Geometry/Outline")
		(27 "Margin" user)
		(31 "F.CrtYd" user "Package Geometry/Place Bound Top")
		(29 "B.CrtYd" user "Package Geometry/Place Bound Bottom")
		(35 "F.Fab" user "Ref Des/Assembly Top")
		(33 "B.Fab" user "Ref Des/Assembly Bottom")
	)
	(footprint ""
		(layer "F.Cu")
		(at 28.578048 -77.783944)
		(property "Reference" "R3143"
			(at 0 0 0)
			(layer "F.SilkS")
			(hide yes)
			(effects
				(font
					(size 1.27 1.27)
				)
			)
		)
		(property "Value" ""
			(at 0 0 0)
			(layer "F.Fab")
			(effects
				(font
					(size 1.27 1.27)
				)
			)
		)
		(duplicate_pad_numbers_are_jumpers no)
		(fp_line
			(start -0.7874 -0.4064)
			(end 0.7874 -0.4064)
			(stroke
				(width 0.1524)
				(type default)
			)
			(layer "F.SilkS")
		)
		(fp_line
			(start -0.7874 0.4064)
			(end -0.7874 -0.4064)
			(stroke
				(width 0.1524)
				(type default)
			)
			(layer "F.SilkS")
		)
		(fp_line
			(start 0.7874 -0.4064)
			(end 0.7874 0.4064)
			(stroke
				(width 0.1524)
				(type default)
			)
			(layer "F.SilkS")
		)
		(fp_line
			(start 0.7874 0.4064)
			(end -0.7874 0.4064)
			(stroke
				(width 0.1524)
				(type default)
			)
			(layer "F.SilkS")
		)
		(fp_line
			(start -0.67945 -0.305054)
			(end -0.12065 -0.305054)
			(stroke
				(width 0.1)
				(type default)
			)
			(layer "F.Fab")
		)
		(fp_line
			(start -0.67945 0.3048)
			(end -0.67945 -0.305054)
			(stroke
				(width 0.1)
				(type default)
			)
			(layer "F.Fab")
		)
		(fp_line
			(start -0.12065 -0.305054)
			(end -0.12065 -0.2794)
			(stroke
				(width 0.1)
				(type default)
			)
			(layer "F.Fab")
		)
		(fp_line
			(start -0.12065 -0.2794)
			(end 0.12065 -0.2794)
			(stroke
				(width 0.1)
				(type default)
			)
			(layer "F.Fab")
		)
		(fp_line
			(start -0.12065 0.2794)
			(end -0.12065 0.3048)
			(stroke
				(width 0.1)
				(type default)
			)
			(layer "F.Fab")
		)
		(fp_line
			(start -0.12065 0.3048)
			(end -0.67945 0.3048)
			(stroke
				(width 0.1)
				(type default)
			)
			(layer "F.Fab")
		)
		(fp_line
			(start 0.120396 0.2794)
			(end -0.12065 0.2794)
			(stroke
				(width 0.1)
				(type default)
			)
			(layer "F.Fab")
		)
		(fp_line
			(start 0.120396 0.3048)
			(end 0.120396 0.2794)
			(stroke
				(width 0.1)
				(type default)
			)
			(layer "F.Fab")
		)
		(fp_line
			(start 0.12065 -0.3048)
			(end 0.67945 -0.3048)
			(stroke
				(width 0.1)
				(type default)
			)
			(layer "F.Fab")
		)
		(fp_line
			(start 0.12065 -0.2794)
			(end 0.12065 -0.3048)
			(stroke
				(width 0.1)
				(type default)
			)
			(layer "F.Fab")
		)
		(fp_line
			(start 0.67945 -0.3048)
			(end 0.67945 0.3048)
			(stroke
				(width 0.1)
				(type default)
			)
			(layer "F.Fab")
		)
		(fp_line
			(start 0.67945 0.3048)
			(end 0.120396 0.3048)
			(stroke
				(width 0.1)
				(type default)
			)
			(layer "F.Fab")
		)
		(pad "1" smd circle
			(at -0.40005 0)
			(size 0 0)
			(layers "F.Cu" "F.Mask" "F.Paste")
			(net "HP_LVC3_OCP_V3_2_PRSNT2_N_R")
		)
		(pad "2" smd circle
			(at 0.40005 0)
			(size 0 0)
			(layers "F.Cu" "F.Mask" "F.Paste")
			(net "HP_LVC3_OCP_V3_2_ATTN_OUT_SW_N")
		)
	)
	(footprint ""
		(layer "F.Cu")
		(at 226.733608 -405.839422 180)
		(property "Reference" "PC2227"
			(at 0 0 180)
			(layer "F.SilkS")
			(hide yes)
			(effects
				(font
					(size 1.27 1.27)
				)
			)
		)
		(property "Value" ""
			(at 0 0 180)
			(layer "F.Fab")
			(effects
				(font
					(size 1.27 1.27)
				)
			)
		)
		(duplicate_pad_numbers_are_jumpers no)
		(fp_line
			(start 0.7874 0.4064)
			(end -0.7874 0.4064)
			(stroke
				(width 0.1524)
				(type default)
			)
			(layer "F.SilkS")
		)
		(fp_line
			(start 0.7874 -0.4064)
			(end 0.7874 0.4064)
			(stroke
				(width 0.1524)
				(type default)
			)
			(layer "F.SilkS")
		)
		(fp_line
			(start -0.7874 0.4064)
			(end -0.7874 -0.4064)
			(stroke
				(width 0.1524)
				(type default)
			)
			(layer "F.SilkS")
		)
		(fp_line
			(start -0.7874 -0.4064)
			(end 0.7874 -0.4064)
			(stroke
				(width 0.1524)
				(type default)
			)
			(layer "F.SilkS")
		)
		(fp_line
			(start 0.67945 0.3048)
			(end 0.120396 0.3048)
			(stroke
				(width 0.1)
				(type default)
			)
			(layer "F.Fab")
		)
		(fp_line
			(start 0.67945 -0.3048)
			(end 0.67945 0.3048)
			(stroke
				(width 0.1)
				(type default)
			)
			(layer "F.Fab")
		)
		(fp_line
			(start 0.12065 -0.2794)
			(end 0.12065 -0.3048)
			(stroke
				(width 0.1)
				(type default)
			)
			(layer "F.Fab")
		)
		(fp_line
			(start 0.12065 -0.3048)
			(end 0.67945 -0.3048)
			(stroke
				(width 0.1)
				(type default)
			)
			(layer "F.Fab")
		)
		(fp_line
			(start 0.120396 0.3048)
			(end 0.120396 0.2794)
			(stroke
				(width 0.1)
				(type default)
			)
			(layer "F.Fab")
		)
		(fp_line
			(start 0.120396 0.2794)
			(end -0.12065 0.2794)
			(stroke
				(width 0.1)
				(type default)
			)
			(layer "F.Fab")
		)
		(fp_line
			(start -0.12065 0.3048)
			(end -0.67945 0.3048)
			(stroke
				(width 0.1)
				(type default)
			)
			(layer "F.Fab")
		)
		(fp_line
			(start -0.12065 0.2794)
			(end -0.12065 0.3048)
			(stroke
				(width 0.1)
				(type default)
			)
			(layer "F.Fab")
		)
		(fp_line
			(start -0.12065 -0.2794)
			(end 0.12065 -0.2794)
			(stroke
				(width 0.1)
				(type default)
			)
			(layer "F.Fab")
		)
		(fp_line
			(start -0.12065 -0.305054)
			(end -0.12065 -0.2794)
			(stroke
				(width 0.1)
				(type default)
			)
			(layer "F.Fab")
		)
		(fp_line
			(start -0.67945 0.3048)
			(end -0.67945 -0.305054)
			(stroke
				(width 0.1)
				(type default)
			)
			(layer "F.Fab")
		)
		(fp_line
			(start -0.67945 -0.305054)
			(end -0.12065 -0.305054)
			(stroke
				(width 0.1)
				(type default)
			)
			(layer "F.Fab")
		)
		(pad "1" smd circle
			(at -0.40005 0 180)
			(size 0 0)
			(layers "F.Cu" "F.Mask" "F.Paste")
			(net "HSC_SS")
		)
		(pad "2" smd circle
			(at 0.40005 0 180)
			(size 0 0)
			(layers "F.Cu" "F.Mask" "F.Paste")
			(net "AGND_HSC")
		)
	)
)
